(kicad_pcb
	(version 20241229)
	(generator "pcbnew")
	(generator_version "9.0")
	(general
		(thickness 1.62)
		(legacy_teardrops no)
	)
	(paper "A3")
	(title_block
		(title "COM Express 7 Baseboard")
		(date "2025-02-04")
		(rev "1.1.2")
		(company "Antmicro Ltd")
		(comment 1 "www.antmicro.com")
		(comment 9 "footprints 456-458 of 802")
	)
	(layers
		(0 "F.Cu" signal)
		(4 "In1.Cu" signal)
		(6 "In2.Cu" signal)
		(8 "In3.Cu" signal)
		(10 "In4.Cu" signal)
		(12 "In5.Cu" signal)
		(14 "In6.Cu" signal)
		(2 "B.Cu" signal)
		(9 "F.Adhes" user "F.Adhesive")
		(11 "B.Adhes" user "B.Adhesive")
		(13 "F.Paste" user)
		(15 "B.Paste" user)
		(5 "F.SilkS" user "F.Silkscreen")
		(7 "B.SilkS" user "B.Silkscreen")
		(1 "F.Mask" user)
		(3 "B.Mask" user)
		(17 "Dwgs.User" user "User.Drawings")
		(19 "Cmts.User" user "User.Comments")
		(21 "Eco1.User" user "User.Eco1")
		(23 "Eco2.User" user "User.Eco2")
		(25 "Edge.Cuts" user)
		(27 "Margin" user)
		(31 "F.CrtYd" user "F.Courtyard")
		(29 "B.CrtYd" user "B.Courtyard")
		(35 "F.Fab" user)
		(33 "B.Fab" user)
	)
	(footprint "antmicro-footprints:SOT-23-3"
		(layer "F.Cu")
		(at 119.45 141.86 180)
		(property "Reference" "Q9"
			(at 1 2.1 90)
			(layer "F.SilkS")
			(effects
				(font
					(size 0.7 0.7)
					(thickness 0.15)
				)
				(justify right bottom)
			)
		)
		(property "Value" "MMBT3904LT1G"
			(at -1.9 2.7 0)
			(layer "F.Fab")
			(effects
				(font
					(size 0.7 0.7)
					(thickness 0.15)
				)
				(justify right bottom)
			)
		)
		(property "Datasheet" "https://eu.mouser.com/datasheet/2/308/1/MMBT3904LT1_D-2316262.pdf"
			(at 0 0 180)
			(layer "F.Fab")
			(hide yes)
			(effects
				(font
					(size 1.27 1.27)
					(thickness 0.15)
				)
			)
		)
		(property "Author" "Antmicro"
			(at 238.9 283.72 0)
			(layer "F.Fab")
			(hide yes)
			(effects
				(font
					(size 1 1)
					(thickness 0.15)
				)
			)
		)
		(property "License" "Apache-2.0"
			(at 238.9 283.72 0)
			(layer "F.Fab")
			(hide yes)
			(effects
				(font
					(size 1 1)
					(thickness 0.15)
				)
			)
		)
		(property "MPN" "MMBT3904LT1G"
			(at 238.9 283.72 0)
			(layer "F.Fab")
			(hide yes)
			(effects
				(font
					(size 1 1)
					(thickness 0.15)
				)
			)
		)
		(property "Manufacturer" "Onsemi"
			(at 238.9 283.72 0)
			(layer "F.Fab")
			(hide yes)
			(effects
				(font
					(size 1 1)
					(thickness 0.15)
				)
			)
		)
		(property "Public" "False"
			(at 238.9 283.72 0)
			(layer "F.Fab")
			(hide yes)
			(effects
				(font
					(size 1 1)
					(thickness 0.15)
				)
			)
		)
		(property ki_fp_filters "SOT?323*")
		(sheetname "Misc")
		(sheetfile "misc.kicad_sch")
		(attr smd)
		(fp_line
			(start 0.7 1.5)
			(end -0.7 1.5)
			(stroke
				(width 0.15)
				(type solid)
			)
			(layer "F.SilkS")
		)
		(fp_line
			(start 0.7 0.4)
			(end 0.7 1.5)
			(stroke
				(width 0.15)
				(type solid)
			)
			(layer "F.SilkS")
		)
		(fp_line
			(start 0.7 -0.4)
			(end 0.7 -1.5)
			(stroke
				(width 0.15)
				(type solid)
			)
			(layer "F.SilkS")
		)
		(fp_line
			(start 0.7 -1.5)
			(end -0.7 -1.5)
			(stroke
				(width 0.15)
				(type solid)
			)
			(layer "F.SilkS")
		)
		(fp_line
			(start -0.7 1.5)
			(end -0.7 1.35)
			(stroke
				(width 0.15)
				(type solid)
			)
			(layer "F.SilkS")
		)
		(fp_line
			(start -0.85 -1.35)
			(end -0.7 -1.5)
			(stroke
				(width 0.15)
				(type solid)
			)
			(layer "F.SilkS")
		)
		(fp_line
			(start -1.45 -1.35)
			(end -0.85 -1.35)
			(stroke
				(width 0.15)
				(type solid)
			)
			(layer "F.SilkS")
		)
		(fp_line
			(start 1.75 0.45)
			(end 0.85 0.45)
			(stroke
				(width 0.05)
				(type solid)
			)
			(layer "F.CrtYd")
		)
		(fp_line
			(start 1.75 -0.45)
			(end 1.75 0.45)
			(stroke
				(width 0.05)
				(type solid)
			)
			(layer "F.CrtYd")
		)
		(fp_line
			(start 0.85 1.65)
			(end -0.85 1.65)
			(stroke
				(width 0.05)
				(type solid)
			)
			(layer "F.CrtYd")
		)
		(fp_line
			(start 0.85 0.45)
			(end 0.85 1.65)
			(stroke
				(width 0.05)
				(type solid)
			)
			(layer "F.CrtYd")
		)
		(fp_line
			(start 0.825 -0.45)
			(end 1.75 -0.45)
			(stroke
				(width 0.05)
				(type solid)
			)
			(layer "F.CrtYd")
		)
		(fp_line
			(start 0.825 -1.6)
			(end 0.825 -0.45)
			(stroke
				(width 0.05)
				(type solid)
			)
			(layer "F.CrtYd")
		)
		(fp_line
			(start -0.85 1.65)
			(end -0.85 1.4)
			(stroke
				(width 0.05)
				(type solid)
			)
			(layer "F.CrtYd")
		)
		(fp_line
			(start -0.85 1.4)
			(end -1.75 1.4)
			(stroke
				(width 0.05)
				(type solid)
			)
			(layer "F.CrtYd")
		)
		(fp_line
			(start -0.85 0.5)
			(end -0.85 -0.5)
			(stroke
				(width 0.05)
				(type solid)
			)
			(layer "F.CrtYd")
		)
		(fp_line
			(start -0.85 -0.5)
			(end -1.75 -0.5)
			(stroke
				(width 0.05)
				(type solid)
			)
			(layer "F.CrtYd")
		)
		(fp_line
			(start -0.9 -1.4)
			(end -1.75 -1.4)
			(stroke
				(width 0.05)
				(type solid)
			)
			(layer "F.CrtYd")
		)
		(fp_line
			(start -0.9 -1.6)
			(end 0.825 -1.6)
			(stroke
				(width 0.05)
				(type solid)
			)
			(layer "F.CrtYd")
		)
		(fp_line
			(start -0.9 -1.6)
			(end -0.9 -1.4)
			(stroke
				(width 0.05)
				(type solid)
			)
			(layer "F.CrtYd")
		)
		(fp_line
			(start -1.75 1.4)
			(end -1.75 0.5)
			(stroke
				(width 0.05)
				(type solid)
			)
			(layer "F.CrtYd")
		)
		(fp_line
			(start -1.75 0.5)
			(end -0.85 0.5)
			(stroke
				(width 0.05)
				(type solid)
			)
			(layer "F.CrtYd")
		)
		(fp_line
			(start -1.75 -0.5)
			(end -1.75 -1.4)
			(stroke
				(width 0.05)
				(type solid)
			)
			(layer "F.CrtYd")
		)
		(fp_line
			(start 0.688 1.519)
			(end 0.688 -1.52)
			(stroke
				(width 0.15)
				(type solid)
			)
			(layer "F.Fab")
		)
		(fp_line
			(start -0.437 -1.526)
			(end 0.688 -1.526)
			(stroke
				(width 0.15)
				(type solid)
			)
			(layer "F.Fab")
		)
		(fp_line
			(start -0.437 -1.526)
			(end -0.712 -1.325)
			(stroke
				(width 0.15)
				(type solid)
			)
			(layer "F.Fab")
		)
		(fp_line
			(start -0.712 1.519)
			(end 0.688 1.519)
			(stroke
				(width 0.15)
				(type solid)
			)
			(layer "F.Fab")
		)
		(fp_line
			(start -0.712 -1.325)
			(end -0.712 1.523)
			(stroke
				(width 0.15)
				(type solid)
			)
			(layer "F.Fab")
		)
		(pad "1" smd roundrect
			(at -1.1 -0.951 180)
			(size 1 0.6)
			(layers "F.Cu" "F.Mask" "F.Paste")
			(roundrect_rratio 0.15)
			(net 541 "Net-(Q9-B)")
			(pinfunction "B")
			(pintype "input")
			(teardrops
				(best_length_ratio 0.2)
				(max_length 1)
				(best_width_ratio 0.9)
				(max_width 2)
				(curved_edges yes)
				(filter_ratio 0.9)
				(enabled yes)
				(allow_two_segments yes)
				(prefer_zone_connections yes)
			)
		)
		(pad "2" smd roundrect
			(at -1.1 0.949 180)
			(size 1 0.6)
			(layers "F.Cu" "F.Mask" "F.Paste")
			(roundrect_rratio 0.15)
			(net 542 "Net-(Q9-E)")
			(pinfunction "E")
			(pintype "passive")
			(teardrops
				(best_length_ratio 0.2)
				(max_length 1)
				(best_width_ratio 0.9)
				(max_width 2)
				(curved_edges yes)
				(filter_ratio 0.9)
				(enabled yes)
				(allow_two_segments yes)
				(prefer_zone_connections yes)
			)
		)
		(pad "3" smd roundrect
			(at 1.1 -0.0005 180)
			(size 1 0.6)
			(layers "F.Cu" "F.Mask" "F.Paste")
			(roundrect_rratio 0.15)
			(net 541 "Net-(Q9-B)")
			(pinfunction "C")
			(pintype "passive")
			(teardrops
				(best_length_ratio 0.2)
				(max_length 1)
				(best_width_ratio 0.9)
				(max_width 2)
				(curved_edges yes)
				(filter_ratio 0.9)
				(enabled yes)
				(allow_two_segments yes)
				(prefer_zone_connections yes)
			)
		)
	)
	(footprint "antmicro-footprints:R_0402_1005Metric"
		(layer "F.Cu")
		(at 241.8 132.36 -90)
		(descr "Resistor SMD 0402")
		(tags "resistor SMD 0402")
		(property "Reference" "R177"
			(at 0.85 -0.45 90)
			(layer "F.SilkS")
			(effects
				(font
					(size 0.7 0.7)
					(thickness 0.15)
				)
				(justify right bottom)
			)
		)
		(property "Value" "R_0R_0402"
			(at -1.011843 1.772047 90)
			(layer "F.Fab")
			(effects
				(font
					(size 0.7 0.7)
					(thickness 0.15)
				)
				(justify right bottom)
			)
		)
		(property "Datasheet" "https://industrial.panasonic.com/cdbs/www-data/pdf/RDA0000/AOA0000C301.pdf"
			(at 0 0 270)
			(layer "F.Fab")
			(hide yes)
			(effects
				(font
					(size 1.27 1.27)
					(thickness 0.15)
				)
			)
		)
		(property "Author" "Antmicro"
			(at 109.44 374.16 0)
			(layer "F.Fab")
			(hide yes)
			(effects
				(font
					(size 1 1)
					(thickness 0.15)
				)
			)
		)
		(property "Current" "1A"
			(at 109.44 374.16 0)
			(layer "F.Fab")
			(hide yes)
			(effects
				(font
					(size 1 1)
					(thickness 0.15)
				)
			)
		)
		(property "License" "Apache-2.0"
			(at 109.44 374.16 0)
			(layer "F.Fab")
			(hide yes)
			(effects
				(font
					(size 1 1)
					(thickness 0.15)
				)
			)
		)
		(property "MPN" "ERJ2GE0R00X"
			(at 109.44 374.16 0)
			(layer "F.Fab")
			(hide yes)
			(effects
				(font
					(size 1 1)
					(thickness 0.15)
				)
			)
		)
		(property "Manufacturer" "Panasonic"
			(at 109.44 374.16 0)
			(layer "F.Fab")
			(hide yes)
			(effects
				(font
					(size 1 1)
					(thickness 0.15)
				)
			)
		)
		(property "Public" "False"
			(at 109.44 374.16 0)
			(layer "F.Fab")
			(hide yes)
			(effects
				(font
					(size 1 1)
					(thickness 0.15)
				)
			)
		)
		(property "Tolerance" ""
			(at 109.44 374.16 0)
			(layer "F.Fab")
			(hide yes)
			(effects
				(font
					(size 1 1)
					(thickness 0.15)
				)
			)
		)
		(property "Val" "0R"
			(at 109.44 374.16 0)
			(layer "F.Fab")
			(hide yes)
			(effects
				(font
					(size 1 1)
					(thickness 0.15)
				)
			)
		)
		(sheetname "Com Express 7 MGMT")
		(sheetfile "com_express_7_mgmt.kicad_sch")
		(attr smd)
		(fp_rect
			(start -0.925 -0.47)
			(end 0.925 0.47)
			(stroke
				(width 0.05)
				(type default)
			)
			(fill no)
			(layer "F.CrtYd")
		)
		(fp_rect
			(start -0.5 -0.25)
			(end 0.5 0.25)
			(stroke
				(width 0.15)
				(type solid)
			)
			(fill no)
			(layer "F.Fab")
		)
		(pad "1" smd roundrect
			(at -0.48 0 270)
			(size 0.59 0.64)
			(layers "F.Cu" "F.Mask" "F.Paste")
			(roundrect_rratio 0.25)
			(net 599 "Net-(U34-~{INT})")
			(pintype "passive")
			(teardrops
				(best_length_ratio 0.2)
				(max_length 1)
				(best_width_ratio 0.9)
				(max_width 2)
				(curved_edges yes)
				(filter_ratio 0.9)
				(enabled yes)
				(allow_two_segments yes)
				(prefer_zone_connections yes)
			)
		)
		(pad "2" smd roundrect
			(at 0.48 0 270)
			(size 0.59 0.64)
			(layers "F.Cu" "F.Mask" "F.Paste")
			(roundrect_rratio 0.25)
			(net 356 "/Com Express 7 MGMT/~{CW_PWRBTN}")
			(pintype "passive")
			(teardrops
				(best_length_ratio 0.2)
				(max_length 1)
				(best_width_ratio 0.9)
				(max_width 2)
				(curved_edges yes)
				(filter_ratio 0.9)
				(enabled yes)
				(allow_two_segments yes)
				(prefer_zone_connections yes)
			)
		)
	)
	(footprint "antmicro-footprints:C_0402_1005Metric"
		(layer "F.Cu")
		(at 196.462003 134.572605 -45)
		(descr "Capacitor SMD 0402")
		(tags "capacitor SMD 0402")
		(property "Reference" "C137"
			(at 3.864616 -0.431761 135)
			(layer "F.SilkS")
			(effects
				(font
					(size 0.7 0.7)
					(thickness 0.15)
				)
				(justify right top)
			)
		)
		(property "Value" "C_100n_0402"
			(at -1.022927 2.155213 135)
			(layer "F.Fab")
			(effects
				(font
					(size 0.7 0.7)
					(thickness 0.15)
				)
				(justify right top)
			)
		)
		(property "Datasheet" "https://www.murata.com/products/productdetail?partno=GRM155R61H104KE14%23"
			(at 0 0 135)
			(layer "B.Fab")
			(hide yes)
			(effects
				(font
					(size 1.27 1.27)
					(thickness 0.15)
				)
				(justify mirror)
			)
		)
		(property "Author" "Antmicro"
			(at 49.668 -322.634 45)
			(layer "F.Fab")
			(hide yes)
			(effects
				(font
					(size 1 1)
					(thickness 0.15)
				)
			)
		)
		(property "Dielectric" "X5R"
			(at 49.668 -322.634 45)
			(layer "F.Fab")
			(hide yes)
			(effects
				(font
					(size 1 1)
					(thickness 0.15)
				)
			)
		)
		(property "License" "Apache-2.0"
			(at 49.668 -322.634 45)
			(layer "F.Fab")
			(hide yes)
			(effects
				(font
					(size 1 1)
					(thickness 0.15)
				)
			)
		)
		(property "MPN" "GRM155R61H104KE14D"
			(at 49.668 -322.634 45)
			(layer "F.Fab")
			(hide yes)
			(effects
				(font
					(size 1 1)
					(thickness 0.15)
				)
			)
		)
		(property "Manufacturer" "Murata"
			(at 49.668 -322.634 45)
			(layer "F.Fab")
			(hide yes)
			(effects
				(font
					(size 1 1)
					(thickness 0.15)
				)
			)
		)
		(property "Public" "False"
			(at 49.668 -322.634 45)
			(layer "F.Fab")
			(hide yes)
			(effects
				(font
					(size 1 1)
					(thickness 0.15)
				)
			)
		)
		(property "Val" "100n"
			(at 49.668 -322.634 45)
			(layer "F.Fab")
			(hide yes)
			(effects
				(font
					(size 1 1)
					(thickness 0.15)
				)
			)
		)
		(property "Voltage" "50V"
			(at 49.668 -322.634 45)
			(layer "F.Fab")
			(hide yes)
			(effects
				(font
					(size 1 1)
					(thickness 0.15)
				)
			)
		)
		(sheetname "PCIe redriver")
		(sheetfile "pcie_redriver.kicad_sch")
		(attr smd)
		(fp_poly
			(pts
				(xy -0.925 -0.47) (xy 0.925 -0.47) (xy 0.925 0.47) (xy -0.925 0.47)
			)
			(stroke
				(width 0.05)
				(type default)
			)
			(fill no)
			(layer "F.CrtYd")
		)
		(fp_line
			(start -0.494 0.248)
			(end -0.494 -0.25)
			(stroke
				(width 0.15)
				(type solid)
			)
			(layer "F.Fab")
		)
		(fp_line
			(start -0.494 -0.25)
			(end 0.504 -0.25)
			(stroke
				(width 0.15)
				(type solid)
			)
			(layer "F.Fab")
		)
		(fp_line
			(start 0.504 0.248)
			(end -0.494 0.248)
			(stroke
				(width 0.15)
				(type solid)
			)
			(layer "F.Fab")
		)
		(fp_line
			(start 0.504 -0.25)
			(end 0.504 0.248)
			(stroke
				(width 0.15)
				(type solid)
			)
			(layer "F.Fab")
		)
		(pad "1" smd roundrect
			(at -0.48 0 315)
			(size 0.59 0.64)
			(layers "F.Cu" "F.Mask" "F.Paste")
			(roundrect_rratio 0.25)
			(net 1 "GND")
			(pintype "passive")
			(teardrops
				(best_length_ratio 0.2)
				(max_length 1)
				(best_width_ratio 0.9)
				(max_width 2)
				(curved_edges yes)
				(filter_ratio 0.9)
				(enabled yes)
				(allow_two_segments yes)
				(prefer_zone_connections yes)
			)
		)
		(pad "2" smd roundrect
			(at 0.48 0 315)
			(size 0.59 0.64)
			(layers "F.Cu" "F.Mask" "F.Paste")
			(roundrect_rratio 0.25)
			(net 2 "+3V3")
			(pintype "passive")
			(teardrops
				(best_length_ratio 0.2)
				(max_length 1)
				(best_width_ratio 0.9)
				(max_width 2)
				(curved_edges yes)
				(filter_ratio 0.9)
				(enabled yes)
				(allow_two_segments yes)
				(prefer_zone_connections yes)
			)
		)
	)
)
